(kicad_pcb
	(version 20260206)
	(generator "pcbnew")
	(generator_version "10.0")
	(general
		(thickness 1.6)
		(legacy_teardrops no)
	)
	(paper "A4")
	(title_block
		(title "03242023_DA0F0TMBIJ0_F0T_Motherboard_J_brd_V01_OCP.brd")
		(comment 1 "Grand Teton / footprints 3983-3989 of 6105")
	)
	(layers
		(0 "F.Cu" signal "TOP")
		(4 "In1.Cu" signal "GND")
		(6 "In2.Cu" signal "IN1")
		(8 "In3.Cu" signal "GND1")
		(10 "In4.Cu" signal "IN2")
		(12 "In5.Cu" signal "GND2")
		(14 "In6.Cu" signal "IN3")
		(16 "In7.Cu" signal "GND3")
		(18 "In8.Cu" signal "VCC")
		(20 "In9.Cu" signal "VCC1")
		(22 "In10.Cu" signal "GND4")
		(24 "In11.Cu" signal "IN4")
		(26 "In12.Cu" signal "GND5")
		(28 "In13.Cu" signal "IN5")
		(30 "In14.Cu" signal "GND6")
		(32 "In15.Cu" signal "IN6")
		(34 "In16.Cu" signal "GND7")
		(2 "B.Cu" signal "BOTTOM")
		(9 "F.Adhes" user "F.Adhesive")
		(11 "B.Adhes" user "B.Adhesive")
		(13 "F.Paste" user "Package Geometry/Pastemask Top")
		(15 "B.Paste" user "Package Geometry/Pastemask Bottom")
		(5 "F.SilkS" user "Ref Des/Silkscreen Top")
		(7 "B.SilkS" user "Ref Des/Silkscreen Bottom")
		(1 "F.Mask" user "Board Geometry/Soldermask Top")
		(3 "B.Mask" user "Board Geometry/Soldermask Bottom")
		(17 "Dwgs.User" user "User.Drawings")
		(19 "Cmts.User" user "User.Comments")
		(21 "Eco1.User" user "User.Eco1")
		(23 "Eco2.User" user "User.Eco2")
		(25 "Edge.Cuts" user "Board Geometry/Outline")
		(27 "Margin" user)
		(31 "F.CrtYd" user "Package Geometry/Place Bound Top")
		(29 "B.CrtYd" user "Package Geometry/Place Bound Bottom")
		(35 "F.Fab" user "Ref Des/Assembly Top")
		(33 "B.Fab" user "Ref Des/Assembly Bottom")
	)
	(footprint ""
		(layer "F.Cu")
		(at 428.63008 -118.34876 180)
		(property "Reference" "PC2365"
			(at 0 0 180)
			(layer "F.SilkS")
			(hide yes)
			(effects
				(font
					(size 1.27 1.27)
				)
			)
		)
		(property "Value" ""
			(at 0 0 180)
			(layer "F.Fab")
			(effects
				(font
					(size 1.27 1.27)
				)
			)
		)
		(duplicate_pad_numbers_are_jumpers no)
		(fp_line
			(start 0.7874 0.4064)
			(end -0.7874 0.4064)
			(stroke
				(width 0.1524)
				(type default)
			)
			(layer "F.SilkS")
		)
		(fp_line
			(start 0.7874 -0.4064)
			(end 0.7874 0.4064)
			(stroke
				(width 0.1524)
				(type default)
			)
			(layer "F.SilkS")
		)
		(fp_line
			(start -0.7874 0.4064)
			(end -0.7874 -0.4064)
			(stroke
				(width 0.1524)
				(type default)
			)
			(layer "F.SilkS")
		)
		(fp_line
			(start -0.7874 -0.4064)
			(end 0.7874 -0.4064)
			(stroke
				(width 0.1524)
				(type default)
			)
			(layer "F.SilkS")
		)
		(fp_line
			(start 0.67945 0.3048)
			(end 0.120396 0.3048)
			(stroke
				(width 0.1)
				(type default)
			)
			(layer "F.Fab")
		)
		(fp_line
			(start 0.67945 -0.3048)
			(end 0.67945 0.3048)
			(stroke
				(width 0.1)
				(type default)
			)
			(layer "F.Fab")
		)
		(fp_line
			(start 0.12065 -0.2794)
			(end 0.12065 -0.3048)
			(stroke
				(width 0.1)
				(type default)
			)
			(layer "F.Fab")
		)
		(fp_line
			(start 0.12065 -0.3048)
			(end 0.67945 -0.3048)
			(stroke
				(width 0.1)
				(type default)
			)
			(layer "F.Fab")
		)
		(fp_line
			(start 0.120396 0.3048)
			(end 0.120396 0.2794)
			(stroke
				(width 0.1)
				(type default)
			)
			(layer "F.Fab")
		)
		(fp_line
			(start 0.120396 0.2794)
			(end -0.12065 0.2794)
			(stroke
				(width 0.1)
				(type default)
			)
			(layer "F.Fab")
		)
		(fp_line
			(start -0.12065 0.3048)
			(end -0.67945 0.3048)
			(stroke
				(width 0.1)
				(type default)
			)
			(layer "F.Fab")
		)
		(fp_line
			(start -0.12065 0.2794)
			(end -0.12065 0.3048)
			(stroke
				(width 0.1)
				(type default)
			)
			(layer "F.Fab")
		)
		(fp_line
			(start -0.12065 -0.2794)
			(end 0.12065 -0.2794)
			(stroke
				(width 0.1)
				(type default)
			)
			(layer "F.Fab")
		)
		(fp_line
			(start -0.12065 -0.305054)
			(end -0.12065 -0.2794)
			(stroke
				(width 0.1)
				(type default)
			)
			(layer "F.Fab")
		)
		(fp_line
			(start -0.67945 0.3048)
			(end -0.67945 -0.305054)
			(stroke
				(width 0.1)
				(type default)
			)
			(layer "F.Fab")
		)
		(fp_line
			(start -0.67945 -0.305054)
			(end -0.12065 -0.305054)
			(stroke
				(width 0.1)
				(type default)
			)
			(layer "F.Fab")
		)
		(pad "1" smd circle
			(at -0.40005 0 180)
			(size 0 0)
			(layers "F.Cu" "F.Mask" "F.Paste")
			(net "PVCCD_HV_CPU0_VCC")
		)
		(pad "2" smd circle
			(at 0.40005 0 180)
			(size 0 0)
			(layers "F.Cu" "F.Mask" "F.Paste")
			(net "GND")
		)
	)
	(footprint ""
		(layer "F.Cu")
		(at 106.70921 -414.741868 180)
		(property "Reference" "R3353"
			(at 0 0 180)
			(layer "F.SilkS")
			(hide yes)
			(effects
				(font
					(size 1.27 1.27)
				)
			)
		)
		(property "Value" ""
			(at 0 0 180)
			(layer "F.Fab")
			(effects
				(font
					(size 1.27 1.27)
				)
			)
		)
		(duplicate_pad_numbers_are_jumpers no)
		(fp_line
			(start 0.7874 -0.4064)
			(end 0.7874 0.09144)
			(stroke
				(width 0.1524)
				(type default)
			)
			(layer "F.SilkS")
		)
		(fp_line
			(start 0.42799 0.4064)
			(end -0.41275 0.4064)
			(stroke
				(width 0.1524)
				(type default)
			)
			(layer "F.SilkS")
		)
		(fp_line
			(start -0.7874 0.03302)
			(end -0.7874 -0.4064)
			(stroke
				(width 0.1524)
				(type default)
			)
			(layer "F.SilkS")
		)
		(fp_line
			(start -0.7874 -0.4064)
			(end 0.7874 -0.4064)
			(stroke
				(width 0.1524)
				(type default)
			)
			(layer "F.SilkS")
		)
		(fp_line
			(start 0.67945 0.3048)
			(end 0.120396 0.3048)
			(stroke
				(width 0.1)
				(type default)
			)
			(layer "F.Fab")
		)
		(fp_line
			(start 0.67945 -0.3048)
			(end 0.67945 0.3048)
			(stroke
				(width 0.1)
				(type default)
			)
			(layer "F.Fab")
		)
		(fp_line
			(start 0.12065 -0.2794)
			(end 0.12065 -0.3048)
			(stroke
				(width 0.1)
				(type default)
			)
			(layer "F.Fab")
		)
		(fp_line
			(start 0.12065 -0.3048)
			(end 0.67945 -0.3048)
			(stroke
				(width 0.1)
				(type default)
			)
			(layer "F.Fab")
		)
		(fp_line
			(start 0.120396 0.3048)
			(end 0.120396 0.2794)
			(stroke
				(width 0.1)
				(type default)
			)
			(layer "F.Fab")
		)
		(fp_line
			(start 0.120396 0.2794)
			(end -0.12065 0.2794)
			(stroke
				(width 0.1)
				(type default)
			)
			(layer "F.Fab")
		)
		(fp_line
			(start -0.12065 0.3048)
			(end -0.67945 0.3048)
			(stroke
				(width 0.1)
				(type default)
			)
			(layer "F.Fab")
		)
		(fp_line
			(start -0.12065 0.2794)
			(end -0.12065 0.3048)
			(stroke
				(width 0.1)
				(type default)
			)
			(layer "F.Fab")
		)
		(fp_line
			(start -0.12065 -0.2794)
			(end 0.12065 -0.2794)
			(stroke
				(width 0.1)
				(type default)
			)
			(layer "F.Fab")
		)
		(fp_line
			(start -0.12065 -0.305054)
			(end -0.12065 -0.2794)
			(stroke
				(width 0.1)
				(type default)
			)
			(layer "F.Fab")
		)
		(fp_line
			(start -0.67945 0.3048)
			(end -0.67945 -0.305054)
			(stroke
				(width 0.1)
				(type default)
			)
			(layer "F.Fab")
		)
		(fp_line
			(start -0.67945 -0.305054)
			(end -0.12065 -0.305054)
			(stroke
				(width 0.1)
				(type default)
			)
			(layer "F.Fab")
		)
		(pad "1" smd circle
			(at -0.40005 0 180)
			(size 0 0)
			(layers "F.Cu" "F.Mask" "F.Paste")
			(net "CLK_100M_GPU_1_R_DN")
		)
		(pad "2" smd circle
			(at 0.40005 0 180)
			(size 0 0)
			(layers "F.Cu" "F.Mask" "F.Paste")
			(net "CLK_100M_GPU_1_DN")
		)
	)
	(footprint ""
		(layer "F.Cu")
		(at 130.665474 -408.517344 -90)
		(property "Reference" "C1522"
			(at 0 0 270)
			(layer "F.SilkS")
			(hide yes)
			(effects
				(font
					(size 1.27 1.27)
				)
			)
		)
		(property "Value" ""
			(at 0 0 270)
			(layer "F.Fab")
			(effects
				(font
					(size 1.27 1.27)
				)
			)
		)
		(duplicate_pad_numbers_are_jumpers no)
		(fp_line
			(start -0.299974 0.150114)
			(end -0.299974 -0.150114)
			(stroke
				(width 0.1)
				(type default)
			)
			(layer "F.Fab")
		)
		(fp_line
			(start 0.299974 0.150114)
			(end -0.299974 0.150114)
			(stroke
				(width 0.1)
				(type default)
			)
			(layer "F.Fab")
		)
		(fp_line
			(start -0.299974 -0.150114)
			(end 0.299974 -0.150114)
			(stroke
				(width 0.1)
				(type default)
			)
			(layer "F.Fab")
		)
		(fp_line
			(start 0.299974 -0.150114)
			(end 0.299974 0.150114)
			(stroke
				(width 0.1)
				(type default)
			)
			(layer "F.Fab")
		)
		(pad "1" smd rect
			(at -0.2667 0 270)
			(size 0.3048 0.381)
			(layers "F.Cu" "F.Mask" "F.Paste")
			(net "P5E_CPU1_PE3_TX_C_DN<12>")
		)
		(pad "2" smd rect
			(at 0.2667 0 270)
			(size 0.3048 0.381)
			(layers "F.Cu" "F.Mask" "F.Paste")
			(net "P5E_CPU1_PE3_TX_DN<12>")
		)
	)
	(footprint ""
		(layer "F.Cu")
		(at 112.40008 -119.846598 -90)
		(property "Reference" "R852"
			(at 0 0 270)
			(layer "F.SilkS")
			(hide yes)
			(effects
				(font
					(size 1.27 1.27)
				)
			)
		)
		(property "Value" ""
			(at 0 0 270)
			(layer "F.Fab")
			(effects
				(font
					(size 1.27 1.27)
				)
			)
		)
		(duplicate_pad_numbers_are_jumpers no)
		(fp_line
			(start -0.7874 0.4064)
			(end -0.7874 -0.4064)
			(stroke
				(width 0.1524)
				(type default)
			)
			(layer "F.SilkS")
		)
		(fp_line
			(start 0.7874 0.4064)
			(end -0.7874 0.4064)
			(stroke
				(width 0.1524)
				(type default)
			)
			(layer "F.SilkS")
		)
		(fp_line
			(start -0.7874 -0.4064)
			(end 0.7874 -0.4064)
			(stroke
				(width 0.1524)
				(type default)
			)
			(layer "F.SilkS")
		)
		(fp_line
			(start 0.7874 -0.4064)
			(end 0.7874 0.4064)
			(stroke
				(width 0.1524)
				(type default)
			)
			(layer "F.SilkS")
		)
		(fp_line
			(start -0.67945 0.3048)
			(end -0.67945 -0.305054)
			(stroke
				(width 0.1)
				(type default)
			)
			(layer "F.Fab")
		)
		(fp_line
			(start -0.12065 0.3048)
			(end -0.67945 0.3048)
			(stroke
				(width 0.1)
				(type default)
			)
			(layer "F.Fab")
		)
		(fp_line
			(start 0.120396 0.3048)
			(end 0.120396 0.2794)
			(stroke
				(width 0.1)
				(type default)
			)
			(layer "F.Fab")
		)
		(fp_line
			(start 0.67945 0.3048)
			(end 0.120396 0.3048)
			(stroke
				(width 0.1)
				(type default)
			)
			(layer "F.Fab")
		)
		(fp_line
			(start -0.12065 0.2794)
			(end -0.12065 0.3048)
			(stroke
				(width 0.1)
				(type default)
			)
			(layer "F.Fab")
		)
		(fp_line
			(start 0.120396 0.2794)
			(end -0.12065 0.2794)
			(stroke
				(width 0.1)
				(type default)
			)
			(layer "F.Fab")
		)
		(fp_line
			(start -0.12065 -0.2794)
			(end 0.12065 -0.2794)
			(stroke
				(width 0.1)
				(type default)
			)
			(layer "F.Fab")
		)
		(fp_line
			(start 0.12065 -0.2794)
			(end 0.12065 -0.3048)
			(stroke
				(width 0.1)
				(type default)
			)
			(layer "F.Fab")
		)
		(fp_line
			(start 0.12065 -0.3048)
			(end 0.67945 -0.3048)
			(stroke
				(width 0.1)
				(type default)
			)
			(layer "F.Fab")
		)
		(fp_line
			(start 0.67945 -0.3048)
			(end 0.67945 0.3048)
			(stroke
				(width 0.1)
				(type default)
			)
			(layer "F.Fab")
		)
		(fp_line
			(start -0.67945 -0.305054)
			(end -0.12065 -0.305054)
			(stroke
				(width 0.1)
				(type default)
			)
			(layer "F.Fab")
		)
		(fp_line
			(start -0.12065 -0.305054)
			(end -0.12065 -0.2794)
			(stroke
				(width 0.1)
				(type default)
			)
			(layer "F.Fab")
		)
		(pad "1" smd circle
			(at -0.40005 0 270)
			(size 0 0)
			(layers "F.Cu" "F.Mask" "F.Paste")
			(net "RST_CPU0_DRAM_CD_N")
		)
		(pad "2" smd circle
			(at 0.40005 0 270)
			(size 0 0)
			(layers "F.Cu" "F.Mask" "F.Paste")
			(net "RST_CPU0_DRAM_CD_PLD_N")
		)
	)
	(footprint ""
		(layer "F.Cu")
		(at 365.46663 -260.364986 -90)
		(property "Reference" "C411"
			(at 0 0 270)
			(layer "F.SilkS")
			(hide yes)
			(effects
				(font
					(size 1.27 1.27)
				)
			)
		)
		(property "Value" ""
			(at 0 0 270)
			(layer "F.Fab")
			(effects
				(font
					(size 1.27 1.27)
				)
			)
		)
		(duplicate_pad_numbers_are_jumpers no)
		(fp_line
			(start -0.7874 0.4064)
			(end -0.7874 -0.4064)
			(stroke
				(width 0.1524)
				(type default)
			)
			(layer "F.SilkS")
		)
		(fp_line
			(start 0.7874 0.4064)
			(end -0.7874 0.4064)
			(stroke
				(width 0.1524)
				(type default)
			)
			(layer "F.SilkS")
		)
		(fp_line
			(start -0.7874 -0.4064)
			(end 0.7874 -0.4064)
			(stroke
				(width 0.1524)
				(type default)
			)
			(layer "F.SilkS")
		)
		(fp_line
			(start 0.7874 -0.4064)
			(end 0.7874 0.4064)
			(stroke
				(width 0.1524)
				(type default)
			)
			(layer "F.SilkS")
		)
		(fp_line
			(start -0.67945 0.3048)
			(end -0.67945 -0.305054)
			(stroke
				(width 0.1)
				(type default)
			)
			(layer "F.Fab")
		)
		(fp_line
			(start -0.12065 0.3048)
			(end -0.67945 0.3048)
			(stroke
				(width 0.1)
				(type default)
			)
			(layer "F.Fab")
		)
		(fp_line
			(start 0.120396 0.3048)
			(end 0.120396 0.2794)
			(stroke
				(width 0.1)
				(type default)
			)
			(layer "F.Fab")
		)
		(fp_line
			(start 0.67945 0.3048)
			(end 0.120396 0.3048)
			(stroke
				(width 0.1)
				(type default)
			)
			(layer "F.Fab")
		)
		(fp_line
			(start -0.12065 0.2794)
			(end -0.12065 0.3048)
			(stroke
				(width 0.1)
				(type default)
			)
			(layer "F.Fab")
		)
		(fp_line
			(start 0.120396 0.2794)
			(end -0.12065 0.2794)
			(stroke
				(width 0.1)
				(type default)
			)
			(layer "F.Fab")
		)
		(fp_line
			(start -0.12065 -0.2794)
			(end 0.12065 -0.2794)
			(stroke
				(width 0.1)
				(type default)
			)
			(layer "F.Fab")
		)
		(fp_line
			(start 0.12065 -0.2794)
			(end 0.12065 -0.3048)
			(stroke
				(width 0.1)
				(type default)
			)
			(layer "F.Fab")
		)
		(fp_line
			(start 0.12065 -0.3048)
			(end 0.67945 -0.3048)
			(stroke
				(width 0.1)
				(type default)
			)
			(layer "F.Fab")
		)
		(fp_line
			(start 0.67945 -0.3048)
			(end 0.67945 0.3048)
			(stroke
				(width 0.1)
				(type default)
			)
			(layer "F.Fab")
		)
		(fp_line
			(start -0.67945 -0.305054)
			(end -0.12065 -0.305054)
			(stroke
				(width 0.1)
				(type default)
			)
			(layer "F.Fab")
		)
		(fp_line
			(start -0.12065 -0.305054)
			(end -0.12065 -0.2794)
			(stroke
				(width 0.1)
				(type default)
			)
			(layer "F.Fab")
		)
		(pad "1" smd circle
			(at -0.40005 0 270)
			(size 0 0)
			(layers "F.Cu" "F.Mask" "F.Paste")
			(net "PVCCFA_EHV_FIVRA_CPU0")
		)
		(pad "2" smd circle
			(at 0.40005 0 270)
			(size 0 0)
			(layers "F.Cu" "F.Mask" "F.Paste")
			(net "GND")
		)
	)
	(footprint ""
		(layer "F.Cu")
		(at 12.982956 -92.687648 90)
		(property "Reference" "R3660"
			(at 0 0 90)
			(layer "F.SilkS")
			(hide yes)
			(effects
				(font
					(size 1.27 1.27)
				)
			)
		)
		(property "Value" ""
			(at 0 0 90)
			(layer "F.Fab")
			(effects
				(font
					(size 1.27 1.27)
				)
			)
		)
		(duplicate_pad_numbers_are_jumpers no)
		(fp_line
			(start 0.7874 -0.4064)
			(end 0.7874 0.4064)
			(stroke
				(width 0.1524)
				(type default)
			)
			(layer "F.SilkS")
		)
		(fp_line
			(start -0.7874 -0.4064)
			(end 0.7874 -0.4064)
			(stroke
				(width 0.1524)
				(type default)
			)
			(layer "F.SilkS")
		)
		(fp_line
			(start 0.7874 0.4064)
			(end -0.7874 0.4064)
			(stroke
				(width 0.1524)
				(type default)
			)
			(layer "F.SilkS")
		)
		(fp_line
			(start -0.7874 0.4064)
			(end -0.7874 -0.4064)
			(stroke
				(width 0.1524)
				(type default)
			)
			(layer "F.SilkS")
		)
		(fp_line
			(start -0.12065 -0.305054)
			(end -0.12065 -0.2794)
			(stroke
				(width 0.1)
				(type default)
			)
			(layer "F.Fab")
		)
		(fp_line
			(start -0.67945 -0.305054)
			(end -0.12065 -0.305054)
			(stroke
				(width 0.1)
				(type default)
			)
			(layer "F.Fab")
		)
		(fp_line
			(start 0.67945 -0.3048)
			(end 0.67945 0.3048)
			(stroke
				(width 0.1)
				(type default)
			)
			(layer "F.Fab")
		)
		(fp_line
			(start 0.12065 -0.3048)
			(end 0.67945 -0.3048)
			(stroke
				(width 0.1)
				(type default)
			)
			(layer "F.Fab")
		)
		(fp_line
			(start 0.12065 -0.2794)
			(end 0.12065 -0.3048)
			(stroke
				(width 0.1)
				(type default)
			)
			(layer "F.Fab")
		)
		(fp_line
			(start -0.12065 -0.2794)
			(end 0.12065 -0.2794)
			(stroke
				(width 0.1)
				(type default)
			)
			(layer "F.Fab")
		)
		(fp_line
			(start 0.120396 0.2794)
			(end -0.12065 0.2794)
			(stroke
				(width 0.1)
				(type default)
			)
			(layer "F.Fab")
		)
		(fp_line
			(start -0.12065 0.2794)
			(end -0.12065 0.3048)
			(stroke
				(width 0.1)
				(type default)
			)
			(layer "F.Fab")
		)
		(fp_line
			(start 0.67945 0.3048)
			(end 0.120396 0.3048)
			(stroke
				(width 0.1)
				(type default)
			)
			(layer "F.Fab")
		)
		(fp_line
			(start 0.120396 0.3048)
			(end 0.120396 0.2794)
			(stroke
				(width 0.1)
				(type default)
			)
			(layer "F.Fab")
		)
		(fp_line
			(start -0.12065 0.3048)
			(end -0.67945 0.3048)
			(stroke
				(width 0.1)
				(type default)
			)
			(layer "F.Fab")
		)
		(fp_line
			(start -0.67945 0.3048)
			(end -0.67945 -0.305054)
			(stroke
				(width 0.1)
				(type default)
			)
			(layer "F.Fab")
		)
		(pad "1" smd circle
			(at -0.40005 0 90)
			(size 0 0)
			(layers "F.Cu" "F.Mask" "F.Paste")
			(net "P3V3_AUX")
		)
		(pad "2" smd circle
			(at 0.40005 0 90)
			(size 0 0)
			(layers "F.Cu" "F.Mask" "F.Paste")
			(net "RST_USB_HUB_R_N")
		)
	)
	(footprint ""
		(layer "F.Cu")
		(at 116.4844 -350.434148 90)
		(property "Reference" "PC2346"
			(at 0 0 90)
			(layer "F.SilkS")
			(hide yes)
			(effects
				(font
					(size 1.27 1.27)
				)
			)
		)
		(property "Value" ""
			(at 0 0 90)
			(layer "F.Fab")
			(effects
				(font
					(size 1.27 1.27)
				)
			)
		)
		(duplicate_pad_numbers_are_jumpers no)
		(fp_line
			(start -3.400044 1.249934)
			(end 3.400044 1.249934)
			(stroke
				(width 0.1524)
				(type default)
			)
			(layer "F.SilkS")
		)
		(fp_circle
			(center 0 1.249934)
			(end 0 4.649978)
			(stroke
				(width 0.1524)
				(type default)
			)
			(fill no)
			(layer "F.SilkS")
		)
		(fp_poly
			(pts
				(arc
					(start -3.400044 1.249934)
					(mid 0 4.649978)
					(end 3.400044 1.249934)
				)
			)
			(stroke
				(width 0)
				(type default)
			)
			(fill yes)
			(layer "F.SilkS")
		)
		(fp_circle
			(center 0 1.249934)
			(end 0 4.649978)
			(stroke
				(width 0.1)
				(type default)
			)
			(fill no)
			(layer "F.Fab")
		)
		(pad "1" thru_hole rect
			(at 0 0 90)
			(size 1.524 1.524)
			(drill 1.016)
			(layers "*.Cu" "*.Mask")
			(remove_unused_layers no)
			(net "SW_P12V_PVCCIN_CPU1_FLT")
			(clearance 0)
			(padstack
				(mode front_inner_back)
				(layer "Inner"
					(shape circle)
					(size 1.524 1.524)
					(clearance 0)
				)
				(layer "B.Cu"
					(shape rect)
					(size 1.524 1.524)
					(clearance 0)
				)
			)
		)
		(pad "2" thru_hole circle
			(at 0 2.500122 90)
			(size 1.524 1.524)
			(drill 1.016)
			(layers "*.Cu" "*.Mask")
			(remove_unused_layers no)
			(net "GND")
			(clearance 0)
		)
	)
)
